(kicad_pcb
	(version 20260206)
	(generator "pcbnew")
	(generator_version "10.0")
	(general
		(thickness 1.6)
		(legacy_teardrops no)
	)
	(paper "A4")
	(title_block
		(title "01162023_DA0F0TEBIF0_F0T_Expander_BD_F_brd_V02_OCP.brd")
		(comment 1 "Grand Teton / footprints 4105-4110 of 9728")
	)
	(layers
		(0 "F.Cu" signal "TOP")
		(4 "In1.Cu" signal "GND")
		(6 "In2.Cu" signal "VCC")
		(8 "In3.Cu" signal "VCC1")
		(10 "In4.Cu" signal "GND1")
		(12 "In5.Cu" signal "IN1")
		(14 "In6.Cu" signal "GND2")
		(16 "In7.Cu" signal "IN2")
		(18 "In8.Cu" signal "GND3")
		(20 "In9.Cu" signal "IN3")
		(22 "In10.Cu" signal "GND4")
		(24 "In11.Cu" signal "IN4")
		(26 "In12.Cu" signal "GND5")
		(28 "In13.Cu" signal "IN5")
		(30 "In14.Cu" signal "GND6")
		(32 "In15.Cu" signal "IN6")
		(34 "In16.Cu" signal "GND7")
		(2 "B.Cu" signal "BOTTOM")
		(9 "F.Adhes" user "F.Adhesive")
		(11 "B.Adhes" user "B.Adhesive")
		(13 "F.Paste" user "Package Geometry/Pastemask Top")
		(15 "B.Paste" user "Package Geometry/Pastemask Bottom")
		(5 "F.SilkS" user "Ref Des/Silkscreen Top")
		(7 "B.SilkS" user "Ref Des/Silkscreen Bottom")
		(1 "F.Mask" user "Board Geometry/Soldermask Top")
		(3 "B.Mask" user "Board Geometry/Soldermask Bottom")
		(17 "Dwgs.User" user "User.Drawings")
		(19 "Cmts.User" user "User.Comments")
		(21 "Eco1.User" user "User.Eco1")
		(23 "Eco2.User" user "User.Eco2")
		(25 "Edge.Cuts" user "Board Geometry/Outline")
		(27 "Margin" user)
		(31 "F.CrtYd" user "Package Geometry/Place Bound Top")
		(29 "B.CrtYd" user "Package Geometry/Place Bound Bottom")
		(35 "F.Fab" user "Ref Des/Assembly Top")
		(33 "B.Fab" user "Ref Des/Assembly Bottom")
	)
	(footprint ""
		(layer "F.Cu")
		(at 211.506816 -366.991646 180)
		(property "Reference" "PR17"
			(at 0 0 180)
			(layer "F.SilkS")
			(hide yes)
			(effects
				(font
					(size 1.27 1.27)
				)
			)
		)
		(property "Value" ""
			(at 0 0 180)
			(layer "F.Fab")
			(effects
				(font
					(size 1.27 1.27)
				)
			)
		)
		(duplicate_pad_numbers_are_jumpers no)
		(fp_line
			(start 0.7874 0.4064)
			(end -0.7874 0.4064)
			(stroke
				(width 0.1524)
				(type default)
			)
			(layer "F.SilkS")
		)
		(fp_line
			(start 0.7874 -0.4064)
			(end 0.7874 0.4064)
			(stroke
				(width 0.1524)
				(type default)
			)
			(layer "F.SilkS")
		)
		(fp_line
			(start -0.7874 0.4064)
			(end -0.7874 -0.4064)
			(stroke
				(width 0.1524)
				(type default)
			)
			(layer "F.SilkS")
		)
		(fp_line
			(start -0.7874 -0.4064)
			(end 0.7874 -0.4064)
			(stroke
				(width 0.1524)
				(type default)
			)
			(layer "F.SilkS")
		)
		(fp_line
			(start 0.67945 0.3048)
			(end 0.120396 0.3048)
			(stroke
				(width 0.1)
				(type default)
			)
			(layer "F.Fab")
		)
		(fp_line
			(start 0.67945 -0.3048)
			(end 0.67945 0.3048)
			(stroke
				(width 0.1)
				(type default)
			)
			(layer "F.Fab")
		)
		(fp_line
			(start 0.12065 -0.2794)
			(end 0.12065 -0.3048)
			(stroke
				(width 0.1)
				(type default)
			)
			(layer "F.Fab")
		)
		(fp_line
			(start 0.12065 -0.3048)
			(end 0.67945 -0.3048)
			(stroke
				(width 0.1)
				(type default)
			)
			(layer "F.Fab")
		)
		(fp_line
			(start 0.120396 0.3048)
			(end 0.120396 0.2794)
			(stroke
				(width 0.1)
				(type default)
			)
			(layer "F.Fab")
		)
		(fp_line
			(start 0.120396 0.2794)
			(end -0.12065 0.2794)
			(stroke
				(width 0.1)
				(type default)
			)
			(layer "F.Fab")
		)
		(fp_line
			(start -0.12065 0.3048)
			(end -0.67945 0.3048)
			(stroke
				(width 0.1)
				(type default)
			)
			(layer "F.Fab")
		)
		(fp_line
			(start -0.12065 0.2794)
			(end -0.12065 0.3048)
			(stroke
				(width 0.1)
				(type default)
			)
			(layer "F.Fab")
		)
		(fp_line
			(start -0.12065 -0.2794)
			(end 0.12065 -0.2794)
			(stroke
				(width 0.1)
				(type default)
			)
			(layer "F.Fab")
		)
		(fp_line
			(start -0.12065 -0.305054)
			(end -0.12065 -0.2794)
			(stroke
				(width 0.1)
				(type default)
			)
			(layer "F.Fab")
		)
		(fp_line
			(start -0.67945 0.3048)
			(end -0.67945 -0.305054)
			(stroke
				(width 0.1)
				(type default)
			)
			(layer "F.Fab")
		)
		(fp_line
			(start -0.67945 -0.305054)
			(end -0.12065 -0.305054)
			(stroke
				(width 0.1)
				(type default)
			)
			(layer "F.Fab")
		)
		(pad "1" smd circle
			(at -0.40005 0 180)
			(size 0 0)
			(layers "F.Cu" "F.Mask" "F.Paste")
			(net "HSC_ON")
		)
		(pad "2" smd circle
			(at 0.40005 0 180)
			(size 0 0)
			(layers "F.Cu" "F.Mask" "F.Paste")
			(net "HSC_ON_R")
		)
	)
	(footprint ""
		(layer "F.Cu")
		(at 361.188 -189.23 180)
		(property "Reference" "R4643"
			(at 0 0 180)
			(layer "F.SilkS")
			(hide yes)
			(effects
				(font
					(size 1.27 1.27)
				)
			)
		)
		(property "Value" ""
			(at 0 0 180)
			(layer "F.Fab")
			(effects
				(font
					(size 1.27 1.27)
				)
			)
		)
		(duplicate_pad_numbers_are_jumpers no)
		(fp_line
			(start 0.7874 0.4064)
			(end -0.7874 0.4064)
			(stroke
				(width 0.1524)
				(type default)
			)
			(layer "F.SilkS")
		)
		(fp_line
			(start 0.7874 -0.4064)
			(end 0.7874 0.4064)
			(stroke
				(width 0.1524)
				(type default)
			)
			(layer "F.SilkS")
		)
		(fp_line
			(start -0.7874 0.4064)
			(end -0.7874 -0.4064)
			(stroke
				(width 0.1524)
				(type default)
			)
			(layer "F.SilkS")
		)
		(fp_line
			(start -0.7874 -0.4064)
			(end 0.7874 -0.4064)
			(stroke
				(width 0.1524)
				(type default)
			)
			(layer "F.SilkS")
		)
		(fp_line
			(start 0.67945 0.3048)
			(end 0.120396 0.3048)
			(stroke
				(width 0.1)
				(type default)
			)
			(layer "F.Fab")
		)
		(fp_line
			(start 0.67945 -0.3048)
			(end 0.67945 0.3048)
			(stroke
				(width 0.1)
				(type default)
			)
			(layer "F.Fab")
		)
		(fp_line
			(start 0.12065 -0.2794)
			(end 0.12065 -0.3048)
			(stroke
				(width 0.1)
				(type default)
			)
			(layer "F.Fab")
		)
		(fp_line
			(start 0.12065 -0.3048)
			(end 0.67945 -0.3048)
			(stroke
				(width 0.1)
				(type default)
			)
			(layer "F.Fab")
		)
		(fp_line
			(start 0.120396 0.3048)
			(end 0.120396 0.2794)
			(stroke
				(width 0.1)
				(type default)
			)
			(layer "F.Fab")
		)
		(fp_line
			(start 0.120396 0.2794)
			(end -0.12065 0.2794)
			(stroke
				(width 0.1)
				(type default)
			)
			(layer "F.Fab")
		)
		(fp_line
			(start -0.12065 0.3048)
			(end -0.67945 0.3048)
			(stroke
				(width 0.1)
				(type default)
			)
			(layer "F.Fab")
		)
		(fp_line
			(start -0.12065 0.2794)
			(end -0.12065 0.3048)
			(stroke
				(width 0.1)
				(type default)
			)
			(layer "F.Fab")
		)
		(fp_line
			(start -0.12065 -0.2794)
			(end 0.12065 -0.2794)
			(stroke
				(width 0.1)
				(type default)
			)
			(layer "F.Fab")
		)
		(fp_line
			(start -0.12065 -0.305054)
			(end -0.12065 -0.2794)
			(stroke
				(width 0.1)
				(type default)
			)
			(layer "F.Fab")
		)
		(fp_line
			(start -0.67945 0.3048)
			(end -0.67945 -0.305054)
			(stroke
				(width 0.1)
				(type default)
			)
			(layer "F.Fab")
		)
		(fp_line
			(start -0.67945 -0.305054)
			(end -0.12065 -0.305054)
			(stroke
				(width 0.1)
				(type default)
			)
			(layer "F.Fab")
		)
		(pad "1" smd circle
			(at -0.40005 0 180)
			(size 0 0)
			(layers "F.Cu" "F.Mask" "F.Paste")
			(net "SSD2_PEX_PWR_EN")
		)
		(pad "2" smd circle
			(at 0.40005 0 180)
			(size 0 0)
			(layers "F.Cu" "F.Mask" "F.Paste")
			(net "SSD2_PEX_PWR_EN_R")
		)
	)
	(footprint ""
		(layer "F.Cu")
		(at 174.6758 -36.915598 -90)
		(property "Reference" "R5559"
			(at 0 0 270)
			(layer "F.SilkS")
			(hide yes)
			(effects
				(font
					(size 1.27 1.27)
				)
			)
		)
		(property "Value" ""
			(at 0 0 270)
			(layer "F.Fab")
			(effects
				(font
					(size 1.27 1.27)
				)
			)
		)
		(duplicate_pad_numbers_are_jumpers no)
		(fp_line
			(start -0.7874 0.4064)
			(end -0.7874 -0.4064)
			(stroke
				(width 0.1524)
				(type default)
			)
			(layer "F.SilkS")
		)
		(fp_line
			(start 0.7874 0.4064)
			(end -0.7874 0.4064)
			(stroke
				(width 0.1524)
				(type default)
			)
			(layer "F.SilkS")
		)
		(fp_line
			(start -0.7874 -0.4064)
			(end 0.7874 -0.4064)
			(stroke
				(width 0.1524)
				(type default)
			)
			(layer "F.SilkS")
		)
		(fp_line
			(start 0.7874 -0.4064)
			(end 0.7874 0.4064)
			(stroke
				(width 0.1524)
				(type default)
			)
			(layer "F.SilkS")
		)
		(fp_line
			(start -0.67945 0.3048)
			(end -0.67945 -0.305054)
			(stroke
				(width 0.1)
				(type default)
			)
			(layer "F.Fab")
		)
		(fp_line
			(start -0.12065 0.3048)
			(end -0.67945 0.3048)
			(stroke
				(width 0.1)
				(type default)
			)
			(layer "F.Fab")
		)
		(fp_line
			(start 0.120396 0.3048)
			(end 0.120396 0.2794)
			(stroke
				(width 0.1)
				(type default)
			)
			(layer "F.Fab")
		)
		(fp_line
			(start 0.67945 0.3048)
			(end 0.120396 0.3048)
			(stroke
				(width 0.1)
				(type default)
			)
			(layer "F.Fab")
		)
		(fp_line
			(start -0.12065 0.2794)
			(end -0.12065 0.3048)
			(stroke
				(width 0.1)
				(type default)
			)
			(layer "F.Fab")
		)
		(fp_line
			(start 0.120396 0.2794)
			(end -0.12065 0.2794)
			(stroke
				(width 0.1)
				(type default)
			)
			(layer "F.Fab")
		)
		(fp_line
			(start -0.12065 -0.2794)
			(end 0.12065 -0.2794)
			(stroke
				(width 0.1)
				(type default)
			)
			(layer "F.Fab")
		)
		(fp_line
			(start 0.12065 -0.2794)
			(end 0.12065 -0.3048)
			(stroke
				(width 0.1)
				(type default)
			)
			(layer "F.Fab")
		)
		(fp_line
			(start 0.12065 -0.3048)
			(end 0.67945 -0.3048)
			(stroke
				(width 0.1)
				(type default)
			)
			(layer "F.Fab")
		)
		(fp_line
			(start 0.67945 -0.3048)
			(end 0.67945 0.3048)
			(stroke
				(width 0.1)
				(type default)
			)
			(layer "F.Fab")
		)
		(fp_line
			(start -0.67945 -0.305054)
			(end -0.12065 -0.305054)
			(stroke
				(width 0.1)
				(type default)
			)
			(layer "F.Fab")
		)
		(fp_line
			(start -0.12065 -0.305054)
			(end -0.12065 -0.2794)
			(stroke
				(width 0.1)
				(type default)
			)
			(layer "F.Fab")
		)
		(pad "1" smd circle
			(at -0.40005 0 270)
			(size 0 0)
			(layers "F.Cu" "F.Mask" "F.Paste")
			(net "PRSNT_SSD6_R1_N")
		)
		(pad "2" smd circle
			(at 0.40005 0 270)
			(size 0 0)
			(layers "F.Cu" "F.Mask" "F.Paste")
			(net "PRSNT_SSD6_R_N")
		)
	)
	(footprint ""
		(layer "F.Cu")
		(at 7.189216 -17.151858 180)
		(property "Reference" "C3874"
			(at 0 0 180)
			(layer "F.SilkS")
			(hide yes)
			(effects
				(font
					(size 1.27 1.27)
				)
			)
		)
		(property "Value" ""
			(at 0 0 180)
			(layer "F.Fab")
			(effects
				(font
					(size 1.27 1.27)
				)
			)
		)
		(duplicate_pad_numbers_are_jumpers no)
		(fp_line
			(start 0.7874 0.4064)
			(end -0.7874 0.4064)
			(stroke
				(width 0.1524)
				(type default)
			)
			(layer "F.SilkS")
		)
		(fp_line
			(start 0.7874 -0.4064)
			(end 0.7874 0.4064)
			(stroke
				(width 0.1524)
				(type default)
			)
			(layer "F.SilkS")
		)
		(fp_line
			(start -0.7874 0.4064)
			(end -0.7874 -0.4064)
			(stroke
				(width 0.1524)
				(type default)
			)
			(layer "F.SilkS")
		)
		(fp_line
			(start -0.7874 -0.4064)
			(end 0.7874 -0.4064)
			(stroke
				(width 0.1524)
				(type default)
			)
			(layer "F.SilkS")
		)
		(fp_line
			(start 0.67945 0.3048)
			(end 0.120396 0.3048)
			(stroke
				(width 0.1)
				(type default)
			)
			(layer "F.Fab")
		)
		(fp_line
			(start 0.67945 -0.3048)
			(end 0.67945 0.3048)
			(stroke
				(width 0.1)
				(type default)
			)
			(layer "F.Fab")
		)
		(fp_line
			(start 0.12065 -0.2794)
			(end 0.12065 -0.3048)
			(stroke
				(width 0.1)
				(type default)
			)
			(layer "F.Fab")
		)
		(fp_line
			(start 0.12065 -0.3048)
			(end 0.67945 -0.3048)
			(stroke
				(width 0.1)
				(type default)
			)
			(layer "F.Fab")
		)
		(fp_line
			(start 0.120396 0.3048)
			(end 0.120396 0.2794)
			(stroke
				(width 0.1)
				(type default)
			)
			(layer "F.Fab")
		)
		(fp_line
			(start 0.120396 0.2794)
			(end -0.12065 0.2794)
			(stroke
				(width 0.1)
				(type default)
			)
			(layer "F.Fab")
		)
		(fp_line
			(start -0.12065 0.3048)
			(end -0.67945 0.3048)
			(stroke
				(width 0.1)
				(type default)
			)
			(layer "F.Fab")
		)
		(fp_line
			(start -0.12065 0.2794)
			(end -0.12065 0.3048)
			(stroke
				(width 0.1)
				(type default)
			)
			(layer "F.Fab")
		)
		(fp_line
			(start -0.12065 -0.2794)
			(end 0.12065 -0.2794)
			(stroke
				(width 0.1)
				(type default)
			)
			(layer "F.Fab")
		)
		(fp_line
			(start -0.12065 -0.305054)
			(end -0.12065 -0.2794)
			(stroke
				(width 0.1)
				(type default)
			)
			(layer "F.Fab")
		)
		(fp_line
			(start -0.67945 0.3048)
			(end -0.67945 -0.305054)
			(stroke
				(width 0.1)
				(type default)
			)
			(layer "F.Fab")
		)
		(fp_line
			(start -0.67945 -0.305054)
			(end -0.12065 -0.305054)
			(stroke
				(width 0.1)
				(type default)
			)
			(layer "F.Fab")
		)
		(pad "1" smd circle
			(at -0.40005 0 180)
			(size 0 0)
			(layers "F.Cu" "F.Mask" "F.Paste")
			(net "P12V_SSD0")
		)
		(pad "2" smd circle
			(at 0.40005 0 180)
			(size 0 0)
			(layers "F.Cu" "F.Mask" "F.Paste")
			(net "GND")
		)
	)
	(footprint ""
		(layer "F.Cu")
		(at 250.30049 -280.573988 180)
		(property "Reference" "PR6616"
			(at 0 0 180)
			(layer "F.SilkS")
			(hide yes)
			(effects
				(font
					(size 1.27 1.27)
				)
			)
		)
		(property "Value" ""
			(at 0 0 180)
			(layer "F.Fab")
			(effects
				(font
					(size 1.27 1.27)
				)
			)
		)
		(duplicate_pad_numbers_are_jumpers no)
		(fp_line
			(start 0.7874 0.4064)
			(end -0.7874 0.4064)
			(stroke
				(width 0.1524)
				(type default)
			)
			(layer "F.SilkS")
		)
		(fp_line
			(start 0.7874 -0.4064)
			(end 0.7874 0.4064)
			(stroke
				(width 0.1524)
				(type default)
			)
			(layer "F.SilkS")
		)
		(fp_line
			(start -0.7874 0.4064)
			(end -0.7874 -0.4064)
			(stroke
				(width 0.1524)
				(type default)
			)
			(layer "F.SilkS")
		)
		(fp_line
			(start -0.7874 -0.4064)
			(end 0.7874 -0.4064)
			(stroke
				(width 0.1524)
				(type default)
			)
			(layer "F.SilkS")
		)
		(fp_line
			(start 0.67945 0.3048)
			(end 0.120396 0.3048)
			(stroke
				(width 0.1)
				(type default)
			)
			(layer "F.Fab")
		)
		(fp_line
			(start 0.67945 -0.3048)
			(end 0.67945 0.3048)
			(stroke
				(width 0.1)
				(type default)
			)
			(layer "F.Fab")
		)
		(fp_line
			(start 0.12065 -0.2794)
			(end 0.12065 -0.3048)
			(stroke
				(width 0.1)
				(type default)
			)
			(layer "F.Fab")
		)
		(fp_line
			(start 0.12065 -0.3048)
			(end 0.67945 -0.3048)
			(stroke
				(width 0.1)
				(type default)
			)
			(layer "F.Fab")
		)
		(fp_line
			(start 0.120396 0.3048)
			(end 0.120396 0.2794)
			(stroke
				(width 0.1)
				(type default)
			)
			(layer "F.Fab")
		)
		(fp_line
			(start 0.120396 0.2794)
			(end -0.12065 0.2794)
			(stroke
				(width 0.1)
				(type default)
			)
			(layer "F.Fab")
		)
		(fp_line
			(start -0.12065 0.3048)
			(end -0.67945 0.3048)
			(stroke
				(width 0.1)
				(type default)
			)
			(layer "F.Fab")
		)
		(fp_line
			(start -0.12065 0.2794)
			(end -0.12065 0.3048)
			(stroke
				(width 0.1)
				(type default)
			)
			(layer "F.Fab")
		)
		(fp_line
			(start -0.12065 -0.2794)
			(end 0.12065 -0.2794)
			(stroke
				(width 0.1)
				(type default)
			)
			(layer "F.Fab")
		)
		(fp_line
			(start -0.12065 -0.305054)
			(end -0.12065 -0.2794)
			(stroke
				(width 0.1)
				(type default)
			)
			(layer "F.Fab")
		)
		(fp_line
			(start -0.67945 0.3048)
			(end -0.67945 -0.305054)
			(stroke
				(width 0.1)
				(type default)
			)
			(layer "F.Fab")
		)
		(fp_line
			(start -0.67945 -0.305054)
			(end -0.12065 -0.305054)
			(stroke
				(width 0.1)
				(type default)
			)
			(layer "F.Fab")
		)
		(pad "1" smd circle
			(at -0.40005 0 180)
			(size 0 0)
			(layers "F.Cu" "F.Mask" "F.Paste")
			(net "SMB_LTC4282_TEMP_SCL")
		)
		(pad "2" smd circle
			(at 0.40005 0 180)
			(size 0 0)
			(layers "F.Cu" "F.Mask" "F.Paste")
			(net "SMB_BIC_I2C6_MUX_PEX_ADC_R_SCL")
		)
	)
	(footprint ""
		(layer "F.Cu")
		(at 457.190602 -244.99824 180)
		(property "Reference" "C4431"
			(at 0 0 180)
			(layer "F.SilkS")
			(hide yes)
			(effects
				(font
					(size 1.27 1.27)
				)
			)
		)
		(property "Value" ""
			(at 0 0 180)
			(layer "F.Fab")
			(effects
				(font
					(size 1.27 1.27)
				)
			)
		)
		(duplicate_pad_numbers_are_jumpers no)
		(fp_line
			(start 1.524 0.762)
			(end -1.524 0.762)
			(stroke
				(width 0.1524)
				(type default)
			)
			(layer "F.SilkS")
		)
		(fp_line
			(start 1.524 -0.762)
			(end 1.524 0.762)
			(stroke
				(width 0.1524)
				(type default)
			)
			(layer "F.SilkS")
		)
		(fp_line
			(start -1.524 0.762)
			(end -1.524 -0.762)
			(stroke
				(width 0.1524)
				(type default)
			)
			(layer "F.SilkS")
		)
		(fp_line
			(start -1.524 -0.762)
			(end 1.524 -0.762)
			(stroke
				(width 0.1524)
				(type default)
			)
			(layer "F.SilkS")
		)
		(fp_line
			(start 1.1049 0.724916)
			(end 1.1049 -0.724916)
			(stroke
				(width 0.1)
				(type default)
			)
			(layer "F.Fab")
		)
		(fp_line
			(start 1.1049 -0.724916)
			(end -1.1049 -0.724916)
			(stroke
				(width 0.1)
				(type default)
			)
			(layer "F.Fab")
		)
		(fp_line
			(start -1.1049 0.724916)
			(end 1.1049 0.724916)
			(stroke
				(width 0.1)
				(type default)
			)
			(layer "F.Fab")
		)
		(fp_line
			(start -1.1049 -0.724916)
			(end -1.1049 0.724916)
			(stroke
				(width 0.1)
				(type default)
			)
			(layer "F.Fab")
		)
		(pad "1" smd rect
			(at -0.889 0)
			(size 1.016 1.27)
			(layers "F.Cu" "F.Mask" "F.Paste")
			(net "P1V8_PLL0_PEX3")
		)
		(pad "2" smd rect
			(at 0.889 0)
			(size 1.016 1.27)
			(layers "F.Cu" "F.Mask" "F.Paste")
			(net "GND")
		)
	)
)
